(kicad_pcb
	(version 20260206)
	(generator "pcbnew")
	(generator_version "10.0")
	(general
		(thickness 1.6)
		(legacy_teardrops no)
	)
	(paper "A4")
	(title_block
		(title "Wiwynn_Tioga_Pass_MB.brd")
		(comment 1 "Tioga Pass / footprints 3872-3879 of 4770")
	)
	(layers
		(0 "F.Cu" signal "TOP")
		(4 "In1.Cu" signal "L2GND")
		(6 "In2.Cu" signal "L3")
		(8 "In3.Cu" signal "L4GND")
		(10 "In4.Cu" signal "L5")
		(12 "In5.Cu" signal "L6GND")
		(14 "In6.Cu" signal "L7VCC")
		(16 "In7.Cu" signal "L8VCC")
		(18 "In8.Cu" signal "L9GND")
		(20 "In9.Cu" signal "L10")
		(22 "In10.Cu" signal "L11GND")
		(24 "In11.Cu" signal "L12")
		(26 "In12.Cu" signal "L13GND")
		(2 "B.Cu" signal "BOTTOM")
		(9 "F.Adhes" user "F.Adhesive")
		(11 "B.Adhes" user "B.Adhesive")
		(13 "F.Paste" user "Package Geometry/Pastemask Top")
		(15 "B.Paste" user "Package Geometry/Pastemask Bottom")
		(5 "F.SilkS" user "Ref Des/Silkscreen Top")
		(7 "B.SilkS" user "Ref Des/Silkscreen Bottom")
		(1 "F.Mask" user "Board Geometry/Soldermask Top")
		(3 "B.Mask" user "Board Geometry/Soldermask Bottom")
		(17 "Dwgs.User" user "User.Drawings")
		(19 "Cmts.User" user "User.Comments")
		(21 "Eco1.User" user "User.Eco1")
		(23 "Eco2.User" user "User.Eco2")
		(25 "Edge.Cuts" user "Board Geometry/Outline")
		(27 "Margin" user)
		(31 "F.CrtYd" user "Package Geometry/Place Bound Top")
		(29 "B.CrtYd" user "Package Geometry/Place Bound Bottom")
		(35 "F.Fab" user "Ref Des/Assembly Top")
		(33 "B.Fab" user "Ref Des/Assembly Bottom")
	)
	(footprint ""
		(layer "B.Cu")
		(at 387.457188 -58.57875 90)
		(property "Reference" "R3T10"
			(at 0 0 90)
			(layer "B.SilkS")
			(hide yes)
			(effects
				(font
					(size 1.27 1.27)
				)
				(justify mirror)
			)
		)
		(property "Value" ""
			(at 0 0 90)
			(layer "B.Fab")
			(effects
				(font
					(size 1.27 1.27)
				)
				(justify mirror)
			)
		)
		(duplicate_pad_numbers_are_jumpers no)
		(fp_poly
			(pts
				(xy 0.2794 -0.1016) (xy -0.2794 -0.1016) (xy -0.2794 0.9906) (xy 0.2794 0.9906)
			)
			(stroke
				(width 0)
				(type default)
			)
			(fill no)
			(layer "B.CrtYd")
		)
		(fp_line
			(start 0.2794 -0.1016)
			(end 0.2794 0.9906)
			(stroke
				(width 0.1)
				(type default)
			)
			(layer "B.Fab")
		)
		(fp_line
			(start -0.2794 -0.1016)
			(end 0.2794 -0.1016)
			(stroke
				(width 0.1)
				(type default)
			)
			(layer "B.Fab")
		)
		(fp_line
			(start 0.2794 0.9906)
			(end -0.2794 0.9906)
			(stroke
				(width 0.1)
				(type default)
			)
			(layer "B.Fab")
		)
		(fp_line
			(start -0.2794 0.9906)
			(end -0.2794 -0.1016)
			(stroke
				(width 0.1)
				(type default)
			)
			(layer "B.Fab")
		)
		(pad "1" smd rect
			(at 0 0 270)
			(size 0.508 0.508)
			(layers "B.Cu" "B.Mask" "B.Paste")
			(net "SPI_SWITCH_MOSI")
		)
		(pad "2" smd rect
			(at 0 0.889 270)
			(size 0.508 0.508)
			(layers "B.Cu" "B.Mask" "B.Paste")
			(net "SPI_SWITCH_MOSI_R1")
		)
		(zone
			(layer "B.Cu")
			(hatch none 0.5)
			(connect_pads
				(clearance 0)
			)
			(min_thickness 0.25)
			(keepout
				(tracks allowed)
				(vias not_allowed)
				(pads allowed)
				(copperpour not_allowed)
				(footprints allowed)
			)
			(placement
				(enabled no)
				(sheetname "")
			)
			(fill
				(thermal_gap 0.5)
				(thermal_bridge_width 0.5)
				(island_removal_mode 0)
			)
			(polygon
				(pts
					(xy 387.711188 -58.83275) (xy 387.711188 -58.32475) (xy 388.092188 -58.32475) (xy 388.092188 -58.83275)
				)
			)
		)
		(zone
			(layer "B.Cu")
			(hatch none 0.5)
			(connect_pads
				(clearance 0)
			)
			(min_thickness 0.25)
			(keepout
				(tracks not_allowed)
				(vias allowed)
				(pads allowed)
				(copperpour not_allowed)
				(footprints allowed)
			)
			(placement
				(enabled no)
				(sheetname "")
			)
			(fill
				(thermal_gap 0.5)
				(thermal_bridge_width 0.5)
				(island_removal_mode 0)
			)
			(polygon
				(pts
					(xy 388.092188 -58.83275) (xy 388.092188 -58.32475) (xy 387.711188 -58.32475) (xy 387.711188 -58.83275)
				)
			)
		)
	)
	(footprint ""
		(layer "B.Cu")
		(at 460.0956 -34.9504 90)
		(property "Reference" "R1U15"
			(at 0 0 90)
			(layer "B.SilkS")
			(hide yes)
			(effects
				(font
					(size 1.27 1.27)
				)
				(justify mirror)
			)
		)
		(property "Value" ""
			(at 0 0 90)
			(layer "B.Fab")
			(effects
				(font
					(size 1.27 1.27)
				)
				(justify mirror)
			)
		)
		(duplicate_pad_numbers_are_jumpers no)
		(fp_poly
			(pts
				(xy 0.2794 -0.1016) (xy -0.2794 -0.1016) (xy -0.2794 0.9906) (xy 0.2794 0.9906)
			)
			(stroke
				(width 0)
				(type default)
			)
			(fill no)
			(layer "B.CrtYd")
		)
		(fp_line
			(start 0.2794 -0.1016)
			(end 0.2794 0.9906)
			(stroke
				(width 0.1)
				(type default)
			)
			(layer "B.Fab")
		)
		(fp_line
			(start -0.2794 -0.1016)
			(end 0.2794 -0.1016)
			(stroke
				(width 0.1)
				(type default)
			)
			(layer "B.Fab")
		)
		(fp_line
			(start 0.2794 0.9906)
			(end -0.2794 0.9906)
			(stroke
				(width 0.1)
				(type default)
			)
			(layer "B.Fab")
		)
		(fp_line
			(start -0.2794 0.9906)
			(end -0.2794 -0.1016)
			(stroke
				(width 0.1)
				(type default)
			)
			(layer "B.Fab")
		)
		(pad "1" smd rect
			(at 0 0 270)
			(size 0.508 0.508)
			(layers "B.Cu" "B.Mask" "B.Paste")
			(net "FM_BOARD_SKU_ID3")
		)
		(pad "2" smd rect
			(at 0 0.889 270)
			(size 0.508 0.508)
			(layers "B.Cu" "B.Mask" "B.Paste")
			(net "GND")
		)
		(zone
			(layer "B.Cu")
			(hatch none 0.5)
			(connect_pads
				(clearance 0)
			)
			(min_thickness 0.25)
			(keepout
				(tracks allowed)
				(vias not_allowed)
				(pads allowed)
				(copperpour not_allowed)
				(footprints allowed)
			)
			(placement
				(enabled no)
				(sheetname "")
			)
			(fill
				(thermal_gap 0.5)
				(thermal_bridge_width 0.5)
				(island_removal_mode 0)
			)
			(polygon
				(pts
					(xy 460.3496 -35.2044) (xy 460.3496 -34.6964) (xy 460.7306 -34.6964) (xy 460.7306 -35.2044)
				)
			)
		)
		(zone
			(layer "B.Cu")
			(hatch none 0.5)
			(connect_pads
				(clearance 0)
			)
			(min_thickness 0.25)
			(keepout
				(tracks not_allowed)
				(vias allowed)
				(pads allowed)
				(copperpour not_allowed)
				(footprints allowed)
			)
			(placement
				(enabled no)
				(sheetname "")
			)
			(fill
				(thermal_gap 0.5)
				(thermal_bridge_width 0.5)
				(island_removal_mode 0)
			)
			(polygon
				(pts
					(xy 460.7306 -35.2044) (xy 460.7306 -34.6964) (xy 460.3496 -34.6964) (xy 460.3496 -35.2044)
				)
			)
		)
	)
	(footprint ""
		(layer "B.Cu")
		(at 32.832802 -58.297064 90)
		(property "Reference" "C9R10"
			(at 0 0 90)
			(layer "B.SilkS")
			(hide yes)
			(effects
				(font
					(size 1.27 1.27)
				)
				(justify mirror)
			)
		)
		(property "Value" ""
			(at 0 0 90)
			(layer "B.Fab")
			(effects
				(font
					(size 1.27 1.27)
				)
				(justify mirror)
			)
		)
		(duplicate_pad_numbers_are_jumpers no)
		(fp_poly
			(pts
				(xy 0.7239 -0.2159) (xy -0.7239 -0.2159) (xy -0.7239 1.9939) (xy 0.7239 1.9939)
			)
			(stroke
				(width 0)
				(type default)
			)
			(fill no)
			(layer "B.CrtYd")
		)
		(fp_line
			(start 0.7239 -0.2159)
			(end 0.7239 1.9939)
			(stroke
				(width 0.1)
				(type default)
			)
			(layer "B.Fab")
		)
		(fp_line
			(start -0.7239 -0.2159)
			(end 0.7239 -0.2159)
			(stroke
				(width 0.1)
				(type default)
			)
			(layer "B.Fab")
		)
		(fp_line
			(start 0.7239 1.9939)
			(end -0.7239 1.9939)
			(stroke
				(width 0.1)
				(type default)
			)
			(layer "B.Fab")
		)
		(fp_line
			(start -0.7239 1.9939)
			(end -0.7239 -0.2159)
			(stroke
				(width 0.1)
				(type default)
			)
			(layer "B.Fab")
		)
		(pad "1" smd rect
			(at 0 0 270)
			(size 1.27 1.016)
			(layers "B.Cu" "B.Mask" "B.Paste")
			(net "VR_FET_SW_P12V_STBY_PVCCIN_CPU1")
		)
		(pad "2" smd rect
			(at 0 1.778 270)
			(size 1.27 1.016)
			(layers "B.Cu" "B.Mask" "B.Paste")
			(net "GND")
		)
		(zone
			(layer "B.Cu")
			(hatch none 0.5)
			(connect_pads
				(clearance 0)
			)
			(min_thickness 0.25)
			(keepout
				(tracks not_allowed)
				(vias allowed)
				(pads allowed)
				(copperpour not_allowed)
				(footprints allowed)
			)
			(placement
				(enabled no)
				(sheetname "")
			)
			(fill
				(thermal_gap 0.5)
				(thermal_bridge_width 0.5)
				(island_removal_mode 0)
			)
			(polygon
				(pts
					(xy 33.340802 -58.932064) (xy 33.340802 -57.662064) (xy 34.102802 -57.662064) (xy 34.102802 -58.932064)
				)
			)
		)
	)
	(footprint ""
		(layer "B.Cu")
		(at 108.432854 -68.17614 180)
		(property "Reference" "C7P20"
			(at 0 0 0)
			(layer "B.SilkS")
			(hide yes)
			(effects
				(font
					(size 1.27 1.27)
				)
				(justify mirror)
			)
		)
		(property "Value" ""
			(at 0 0 0)
			(layer "B.Fab")
			(effects
				(font
					(size 1.27 1.27)
				)
				(justify mirror)
			)
		)
		(duplicate_pad_numbers_are_jumpers no)
		(fp_poly
			(pts
				(xy 0.7239 -0.2159) (xy -0.7239 -0.2159) (xy -0.7239 1.9939) (xy 0.7239 1.9939)
			)
			(stroke
				(width 0)
				(type default)
			)
			(fill no)
			(layer "B.CrtYd")
		)
		(fp_line
			(start 0.7239 1.9939)
			(end -0.7239 1.9939)
			(stroke
				(width 0.1)
				(type default)
			)
			(layer "B.Fab")
		)
		(fp_line
			(start 0.7239 -0.2159)
			(end 0.7239 1.9939)
			(stroke
				(width 0.1)
				(type default)
			)
			(layer "B.Fab")
		)
		(fp_line
			(start -0.7239 1.9939)
			(end -0.7239 -0.2159)
			(stroke
				(width 0.1)
				(type default)
			)
			(layer "B.Fab")
		)
		(fp_line
			(start -0.7239 -0.2159)
			(end 0.7239 -0.2159)
			(stroke
				(width 0.1)
				(type default)
			)
			(layer "B.Fab")
		)
		(pad "1" smd rect
			(at 0 0)
			(size 1.27 1.016)
			(layers "B.Cu" "B.Mask" "B.Paste")
			(net "PVDDQ_GHJ")
		)
		(pad "2" smd rect
			(at 0 1.778)
			(size 1.27 1.016)
			(layers "B.Cu" "B.Mask" "B.Paste")
			(net "GND")
		)
		(zone
			(layer "B.Cu")
			(hatch none 0.5)
			(connect_pads
				(clearance 0)
			)
			(min_thickness 0.25)
			(keepout
				(tracks not_allowed)
				(vias allowed)
				(pads allowed)
				(copperpour not_allowed)
				(footprints allowed)
			)
			(placement
				(enabled no)
				(sheetname "")
			)
			(fill
				(thermal_gap 0.5)
				(thermal_bridge_width 0.5)
				(island_removal_mode 0)
			)
			(polygon
				(pts
					(xy 107.797854 -68.68414) (xy 109.067854 -68.68414) (xy 109.067854 -69.44614) (xy 107.797854 -69.44614)
				)
			)
		)
	)
	(footprint ""
		(layer "B.Cu")
		(at 477.848422 -132.838444)
		(property "Reference" "R1W39"
			(at 0.8382 -0.67818 0)
			(unlocked yes)
			(layer "B.SilkS")
			(effects
				(font
					(size 0.4064 0.254)
					(thickness 0.1524)
				)
				(justify left mirror)
			)
		)
		(property "Value" ""
			(at 0 0 0)
			(layer "B.Fab")
			(effects
				(font
					(size 1.27 1.27)
				)
				(justify mirror)
			)
		)
		(duplicate_pad_numbers_are_jumpers no)
		(fp_poly
			(pts
				(xy 0.2794 -0.1016) (xy -0.2794 -0.1016) (xy -0.2794 0.9906) (xy 0.2794 0.9906)
			)
			(stroke
				(width 0)
				(type default)
			)
			(fill no)
			(layer "B.CrtYd")
		)
		(fp_line
			(start -0.2794 -0.1016)
			(end 0.2794 -0.1016)
			(stroke
				(width 0.1)
				(type default)
			)
			(layer "B.Fab")
		)
		(fp_line
			(start -0.2794 0.9906)
			(end -0.2794 -0.1016)
			(stroke
				(width 0.1)
				(type default)
			)
			(layer "B.Fab")
		)
		(fp_line
			(start 0.2794 -0.1016)
			(end 0.2794 0.9906)
			(stroke
				(width 0.1)
				(type default)
			)
			(layer "B.Fab")
		)
		(fp_line
			(start 0.2794 0.9906)
			(end -0.2794 0.9906)
			(stroke
				(width 0.1)
				(type default)
			)
			(layer "B.Fab")
		)
		(pad "1" smd rect
			(at 0 0 180)
			(size 0.508 0.508)
			(layers "B.Cu" "B.Mask" "B.Paste")
			(net "SMB_DEBUG_STBY_LVC3_SDA_CONN")
		)
		(pad "2" smd rect
			(at 0 0.889 180)
			(size 0.508 0.508)
			(layers "B.Cu" "B.Mask" "B.Paste")
			(net "SMB_DEBUG_STBY_LVC3_SDA_R1")
		)
		(zone
			(layer "B.Cu")
			(hatch none 0.5)
			(connect_pads
				(clearance 0)
			)
			(min_thickness 0.25)
			(keepout
				(tracks allowed)
				(vias not_allowed)
				(pads allowed)
				(copperpour not_allowed)
				(footprints allowed)
			)
			(placement
				(enabled no)
				(sheetname "")
			)
			(fill
				(thermal_gap 0.5)
				(thermal_bridge_width 0.5)
				(island_removal_mode 0)
			)
			(polygon
				(pts
					(xy 478.102422 -132.584444) (xy 477.594422 -132.584444) (xy 477.594422 -132.203444) (xy 478.102422 -132.203444)
				)
			)
		)
		(zone
			(layer "B.Cu")
			(hatch none 0.5)
			(connect_pads
				(clearance 0)
			)
			(min_thickness 0.25)
			(keepout
				(tracks not_allowed)
				(vias allowed)
				(pads allowed)
				(copperpour not_allowed)
				(footprints allowed)
			)
			(placement
				(enabled no)
				(sheetname "")
			)
			(fill
				(thermal_gap 0.5)
				(thermal_bridge_width 0.5)
				(island_removal_mode 0)
			)
			(polygon
				(pts
					(xy 478.102422 -132.203444) (xy 477.594422 -132.203444) (xy 477.594422 -132.584444) (xy 478.102422 -132.584444)
				)
			)
		)
	)
	(footprint ""
		(layer "B.Cu")
		(at 94.06636 -149.7711 90)
		(property "Reference" "C5G116"
			(at -1.64973 0.78994 180)
			(unlocked yes)
			(layer "B.SilkS")
			(effects
				(font
					(size 0.7874 0.5842)
					(thickness 0.1524)
				)
				(justify mirror)
			)
		)
		(property "Value" ""
			(at 0 0 90)
			(layer "B.Fab")
			(effects
				(font
					(size 1.27 1.27)
				)
				(justify mirror)
			)
		)
		(duplicate_pad_numbers_are_jumpers no)
		(fp_rect
			(start -0.7239 -0.2159)
			(end 0.7239 1.9939)
			(stroke
				(width 0)
				(type default)
			)
			(fill no)
			(layer "B.CrtYd")
		)
		(fp_line
			(start 0.7239 -0.2159)
			(end 0.7239 1.9939)
			(stroke
				(width 0.1)
				(type default)
			)
			(layer "B.Fab")
		)
		(fp_line
			(start -0.7239 -0.2159)
			(end 0.7239 -0.2159)
			(stroke
				(width 0.1)
				(type default)
			)
			(layer "B.Fab")
		)
		(fp_line
			(start 0.7239 1.9939)
			(end -0.7239 1.9939)
			(stroke
				(width 0.1)
				(type default)
			)
			(layer "B.Fab")
		)
		(fp_line
			(start -0.7239 1.9939)
			(end -0.7239 -0.2159)
			(stroke
				(width 0.1)
				(type default)
			)
			(layer "B.Fab")
		)
		(pad "1" smd rect
			(at 0 0 270)
			(size 1.27 1.016)
			(layers "B.Cu" "B.Mask" "B.Paste")
			(net "PVDDQ_KLM")
		)
		(pad "2" smd rect
			(at 0 1.778 270)
			(size 1.27 1.016)
			(layers "B.Cu" "B.Mask" "B.Paste")
			(net "GND")
		)
		(zone
			(layer "B.Cu")
			(hatch none 0.5)
			(connect_pads
				(clearance 0)
			)
			(min_thickness 0.25)
			(keepout
				(tracks not_allowed)
				(vias allowed)
				(pads allowed)
				(copperpour not_allowed)
				(footprints allowed)
			)
			(placement
				(enabled no)
				(sheetname "")
			)
			(fill
				(thermal_gap 0.5)
				(thermal_bridge_width 0.5)
				(island_removal_mode 0)
			)
			(polygon
				(pts
					(xy 94.57436 -149.1361) (xy 95.33636 -149.1361) (xy 95.33636 -150.4061) (xy 94.57436 -150.4061)
				)
			)
		)
	)
	(footprint ""
		(layer "B.Cu")
		(at 475.187518 -15.517876 180)
		(property "Reference" "C8F17"
			(at 0 0 0)
			(layer "B.SilkS")
			(hide yes)
			(effects
				(font
					(size 1.27 1.27)
				)
				(justify mirror)
			)
		)
		(property "Value" ""
			(at 0 0 0)
			(layer "B.Fab")
			(effects
				(font
					(size 1.27 1.27)
				)
				(justify mirror)
			)
		)
		(duplicate_pad_numbers_are_jumpers no)
		(fp_rect
			(start 0.3048 0.9906)
			(end -0.3048 -0.1016)
			(stroke
				(width 0)
				(type default)
			)
			(fill no)
			(layer "B.CrtYd")
		)
		(fp_line
			(start 0.3048 0.9906)
			(end -0.3048 0.9906)
			(stroke
				(width 0.1)
				(type default)
			)
			(layer "B.Fab")
		)
		(fp_line
			(start 0.3048 -0.1016)
			(end 0.3048 0.9906)
			(stroke
				(width 0.1)
				(type default)
			)
			(layer "B.Fab")
		)
		(fp_line
			(start -0.3048 0.9906)
			(end -0.3048 -0.1016)
			(stroke
				(width 0.1)
				(type default)
			)
			(layer "B.Fab")
		)
		(fp_line
			(start -0.3048 -0.1016)
			(end 0.3048 -0.1016)
			(stroke
				(width 0.1)
				(type default)
			)
			(layer "B.Fab")
		)
		(pad "1" smd rect
			(at 0 0)
			(size 0.508 0.508)
			(layers "B.Cu" "B.Mask" "B.Paste")
			(net "P5V_STBY")
		)
		(pad "2" smd rect
			(at 0 0.889)
			(size 0.508 0.508)
			(layers "B.Cu" "B.Mask" "B.Paste")
			(net "GND")
		)
		(zone
			(layer "B.Cu")
			(hatch none 0.5)
			(connect_pads
				(clearance 0)
			)
			(min_thickness 0.25)
			(keepout
				(tracks not_allowed)
				(vias allowed)
				(pads allowed)
				(copperpour not_allowed)
				(footprints allowed)
			)
			(placement
				(enabled no)
				(sheetname "")
			)
			(fill
				(thermal_gap 0.5)
				(thermal_bridge_width 0.5)
				(island_removal_mode 0)
			)
			(polygon
				(pts
					(xy 474.933518 -16.152876) (xy 474.933518 -15.771876) (xy 475.441518 -15.771876) (xy 475.441518 -16.152876)
				)
			)
		)
		(zone
			(layer "B.Cu")
			(hatch none 0.5)
			(connect_pads
				(clearance 0)
			)
			(min_thickness 0.25)
			(keepout
				(tracks allowed)
				(vias not_allowed)
				(pads allowed)
				(copperpour not_allowed)
				(footprints allowed)
			)
			(placement
				(enabled no)
				(sheetname "")
			)
			(fill
				(thermal_gap 0.5)
				(thermal_bridge_width 0.5)
				(island_removal_mode 0)
			)
			(polygon
				(pts
					(xy 474.933518 -16.152876) (xy 474.933518 -15.771876) (xy 475.441518 -15.771876) (xy 475.441518 -16.152876)
				)
			)
		)
	)
	(footprint ""
		(layer "B.Cu")
		(at 385.33705 -107.05465 90)
		(property "Reference" "C3N18"
			(at 0 0 90)
			(layer "B.SilkS")
			(hide yes)
			(effects
				(font
					(size 1.27 1.27)
				)
				(justify mirror)
			)
		)
		(property "Value" ""
			(at 0 0 90)
			(layer "B.Fab")
			(effects
				(font
					(size 1.27 1.27)
				)
				(justify mirror)
			)
		)
		(duplicate_pad_numbers_are_jumpers no)
		(fp_rect
			(start 0.2794 0.9144)
			(end -0.2794 -0.1143)
			(stroke
				(width 0)
				(type default)
			)
			(fill no)
			(layer "B.CrtYd")
		)
		(fp_line
			(start 0.2794 -0.1143)
			(end -0.2794 -0.1143)
			(stroke
				(width 0.1)
				(type default)
			)
			(layer "B.Fab")
		)
		(fp_line
			(start -0.2794 -0.1143)
			(end -0.2794 0.9144)
			(stroke
				(width 0.1)
				(type default)
			)
			(layer "B.Fab")
		)
		(fp_line
			(start 0.2794 0.9144)
			(end 0.2794 -0.1143)
			(stroke
				(width 0.1)
				(type default)
			)
			(layer "B.Fab")
		)
		(fp_line
			(start -0.2794 0.9144)
			(end 0.2794 0.9144)
			(stroke
				(width 0.1)
				(type default)
			)
			(layer "B.Fab")
		)
		(pad "1" smd custom
			(at 0 0)
			(size 0.10414 0.10414)
			(layers "B.Cu" "B.Mask" "B.Paste")
			(net "PVNN_PCH_STBY")
			(options
				(clearance outline)
				(anchor circle)
			)
			(primitives
				(gr_poly
					(pts
						(xy -0.20828 -0.08636) (xy -0.20828 0.08636) (xy -0.08636 0.20828) (xy 0.086614 0.20828) (xy 0.20828 0.086614)
						(xy 0.20828 -0.08636) (xy 0.08636 -0.20828) (xy -0.08636 -0.20828)
					)
					(width 0)
					(fill yes)
				)
			)
		)
		(pad "2" smd custom
			(at 0 0.8001)
			(size 0.10414 0.10414)
			(layers "B.Cu" "B.Mask" "B.Paste")
			(net "GND")
			(options
				(clearance outline)
				(anchor circle)
			)
			(primitives
				(gr_poly
					(pts
						(xy -0.20828 -0.08636) (xy -0.20828 0.08636) (xy -0.08636 0.20828) (xy 0.086614 0.20828) (xy 0.20828 0.086614)
						(xy 0.20828 -0.08636) (xy 0.08636 -0.20828) (xy -0.08636 -0.20828)
					)
					(width 0)
					(fill yes)
				)
			)
		)
		(zone
			(layer "B.Cu")
			(hatch none 0.5)
			(connect_pads
				(clearance 0)
			)
			(min_thickness 0.25)
			(keepout
				(tracks allowed)
				(vias not_allowed)
				(pads allowed)
				(copperpour not_allowed)
				(footprints allowed)
			)
			(placement
				(enabled no)
				(sheetname "")
			)
			(fill
				(thermal_gap 0.5)
				(thermal_bridge_width 0.5)
				(island_removal_mode 0)
			)
			(polygon
				(pts
					(xy 385.5466 -107.14228) (xy 385.9276 -107.14228) (xy 385.9276 -106.96702) (xy 385.5466 -106.966766)
				)
			)
		)
		(zone
			(layer "B.Cu")
			(hatch none 0.5)
			(connect_pads
				(clearance 0)
			)
			(min_thickness 0.25)
			(keepout
				(tracks not_allowed)
				(vias allowed)
				(pads allowed)
				(copperpour not_allowed)
				(footprints allowed)
			)
			(placement
				(enabled no)
				(sheetname "")
			)
			(fill
				(thermal_gap 0.5)
				(thermal_bridge_width 0.5)
				(island_removal_mode 0)
			)
			(polygon
				(pts
					(xy 385.5466 -107.14228) (xy 385.9276 -107.14228) (xy 385.9276 -106.96702) (xy 385.5466 -106.966766)
				)
			)
		)
	)
)
